(kicad_pcb
	(version 20241229)
	(generator "pcbnew")
	(generator_version "9.0")
	(general
		(thickness 1.63)
		(legacy_teardrops no)
	)
	(paper "A4")
	(title_block
		(title "CM4 Baseboard")
		(date "2026-01-05")
		(rev "1.1.1")
		(company "Antmicro Ltd")
		(comment 1 "www.antmicro.com")
		(comment 9 "footprint 307 of 506 (U905), pads 1-77 of 77")
	)
	(layers
		(0 "F.Cu" signal)
		(4 "In1.Cu" power)
		(6 "In2.Cu" power)
		(8 "In3.Cu" signal)
		(10 "In4.Cu" signal)
		(2 "B.Cu" signal)
		(9 "F.Adhes" user "F.Adhesive")
		(11 "B.Adhes" user "B.Adhesive")
		(13 "F.Paste" user)
		(15 "B.Paste" user)
		(5 "F.SilkS" user "F.Silkscreen")
		(7 "B.SilkS" user "B.Silkscreen")
		(1 "F.Mask" user)
		(3 "B.Mask" user)
		(17 "Dwgs.User" user "User.Drawings")
		(19 "Cmts.User" user "User.Comments")
		(21 "Eco1.User" user "User.Eco1")
		(23 "Eco2.User" user "User.Eco2")
		(25 "Edge.Cuts" user)
		(27 "Margin" user)
		(31 "F.CrtYd" user "F.Courtyard")
		(29 "B.CrtYd" user "B.Courtyard")
		(35 "F.Fab" user)
		(33 "B.Fab" user)
	)
	(footprint "antmicro-footprints:QFN-76-1EP_9x9mm_P0.4mm_EP6.3x6.3mm"
		(layer "F.Cu")
		(at 89.667962 138.307236)
		(property "Reference" "U905"
			(at -7.73 4.379264 0)
			(layer "F.SilkS")
			(effects
				(font
					(size 0.7 0.7)
					(thickness 0.15)
				)
				(justify left bottom)
			)
		)
		(property "Value" "FT4233HPQ"
			(at 0.1 6.2 0)
			(layer "F.Fab")
			(effects
				(font
					(size 0.7 0.7)
					(thickness 0.15)
				)
				(justify left bottom)
			)
		)
		(property "Datasheet" "https://ftdichip.com/wp-content/uploads/2023/09/DS_FT4233HP-v1.5.pdf"
			(at 0 0 0)
			(layer "F.Fab")
			(hide yes)
			(effects
				(font
					(size 1.27 1.27)
					(thickness 0.15)
				)
			)
		)
		(property "MPN" "FT4233HPQ-REEL"
			(at 0 0 0)
			(unlocked yes)
			(layer "F.Fab")
			(hide yes)
			(effects
				(font
					(size 1 1)
					(thickness 0.15)
				)
			)
		)
		(property "Manufacturer" "FTDI Chip"
			(at 0 0 0)
			(unlocked yes)
			(layer "F.Fab")
			(hide yes)
			(effects
				(font
					(size 1 1)
					(thickness 0.15)
				)
			)
		)
		(property "License" "Apache-2.0"
			(at 0 0 0)
			(unlocked yes)
			(layer "F.Fab")
			(hide yes)
			(effects
				(font
					(size 1 1)
					(thickness 0.15)
				)
			)
		)
		(property "Author" "Antmicro"
			(at 0 0 0)
			(unlocked yes)
			(layer "F.Fab")
			(hide yes)
			(effects
				(font
					(size 1 1)
					(thickness 0.15)
				)
			)
		)
		(sheetname "/USB/")
		(sheetfile "usb.kicad_sch")
		(attr smd)
		(pad "1" smd rect
			(at -4.35 -3.6)
			(size 0.7 0.2)
			(layers "F.Cu" "F.Mask" "F.Paste")
			(net 282 "/USB/EECLK")
			(pinfunction "EECLK")
			(pintype "output")
		)
		(pad "2" smd rect
			(at -4.35 -3.2)
			(size 0.7 0.2)
			(layers "F.Cu" "F.Mask" "F.Paste")
			(net 281 "/USB/EEDATA")
			(pinfunction "EEDATA")
			(pintype "bidirectional")
		)
		(pad "3" smd rect
			(at -4.35 -2.8)
			(size 0.7 0.2)
			(layers "F.Cu" "F.Mask" "F.Paste")
			(net 3 "GND")
			(pinfunction "TEST")
			(pintype "input")
		)
		(pad "4" smd rect
			(at -4.35 -2.4)
			(size 0.7 0.2)
			(layers "F.Cu" "F.Mask" "F.Paste")
			(net 379 "Net-(U905-~{RESET})")
			(pinfunction "~{RESET}")
			(pintype "input")
		)
		(pad "5" smd rect
			(at -4.35 -2)
			(size 0.7 0.2)
			(layers "F.Cu" "F.Mask" "F.Paste")
			(net 338 "/USB/USBD_IN_EN")
			(pinfunction "GPIO3")
			(pintype "bidirectional")
		)
		(pad "6" smd rect
			(at -4.35 -1.6)
			(size 0.7 0.2)
			(layers "F.Cu" "F.Mask" "F.Paste")
			(net 441 "Net-(U905-GPIO4)")
			(pinfunction "GPIO4")
			(pintype "bidirectional")
		)
		(pad "7" smd rect
			(at -4.35 -1.2)
			(size 0.7 0.2)
			(layers "F.Cu" "F.Mask" "F.Paste")
			(net 442 "Net-(U905-GPIO5)")
			(pinfunction "GPIO5")
			(pintype "bidirectional")
		)
		(pad "8" smd rect
			(at -4.35 -0.8)
			(size 0.7 0.2)
			(layers "F.Cu" "F.Mask" "F.Paste")
			(net 36 "/Compute module/UART.0.RX")
			(pinfunction "ADBUS0")
			(pintype "bidirectional")
		)
		(pad "9" smd rect
			(at -4.35 -0.4)
			(size 0.7 0.2)
			(layers "F.Cu" "F.Mask" "F.Paste")
			(net 37 "/Compute module/UART.0.TX")
			(pinfunction "ADBUS1")
			(pintype "bidirectional")
		)
		(pad "10" smd rect
			(at -4.35 0)
			(size 0.7 0.2)
			(layers "F.Cu" "F.Mask" "F.Paste")
			(net 30 "/USB/USB_1V2")
			(pinfunction "VCORE")
			(pintype "power_in")
		)
		(pad "11" smd rect
			(at -4.35 0.4)
			(size 0.7 0.2)
			(layers "F.Cu" "F.Mask" "F.Paste")
			(net 3 "GND")
			(pinfunction "GND")
			(pintype "power_in")
		)
		(pad "12" smd rect
			(at -4.35 0.8)
			(size 0.7 0.2)
			(layers "F.Cu" "F.Mask" "F.Paste")
			(net 27 "/USB/USB_3V3")
			(pinfunction "VCCIO")
			(pintype "power_in")
		)
		(pad "13" smd rect
			(at -4.35 1.2)
			(size 0.7 0.2)
			(layers "F.Cu" "F.Mask" "F.Paste")
			(net 431 "unconnected-(U905-ADBUS2-Pad13)")
			(pinfunction "ADBUS2")
			(pintype "bidirectional+no_connect")
		)
		(pad "14" smd rect
			(at -4.35 1.6)
			(size 0.7 0.2)
			(layers "F.Cu" "F.Mask" "F.Paste")
			(net 430 "unconnected-(U905-ADBUS3-Pad14)")
			(pinfunction "ADBUS3")
			(pintype "bidirectional+no_connect")
		)
		(pad "15" smd rect
			(at -4.35 2)
			(size 0.7 0.2)
			(layers "F.Cu" "F.Mask" "F.Paste")
			(net 429 "unconnected-(U905-ADBUS4-Pad15)")
			(pinfunction "ADBUS4")
			(pintype "bidirectional+no_connect")
		)
		(pad "16" smd rect
			(at -4.35 2.4)
			(size 0.7 0.2)
			(layers "F.Cu" "F.Mask" "F.Paste")
			(net 428 "unconnected-(U905-ADBUS5-Pad16)")
			(pinfunction "ADBUS5")
			(pintype "bidirectional+no_connect")
		)
		(pad "17" smd rect
			(at -4.35 2.8)
			(size 0.7 0.2)
			(layers "F.Cu" "F.Mask" "F.Paste")
			(net 427 "unconnected-(U905-ADBUS6-Pad17)")
			(pinfunction "ADBUS6")
			(pintype "bidirectional+no_connect")
		)
		(pad "18" smd rect
			(at -4.35 3.2)
			(size 0.7 0.2)
			(layers "F.Cu" "F.Mask" "F.Paste")
			(net 426 "unconnected-(U905-ADBUS7-Pad18)")
			(pinfunction "ADBUS7")
			(pintype "bidirectional+no_connect")
		)
		(pad "19" smd rect
			(at -4.35 3.6)
			(size 0.7 0.2)
			(layers "F.Cu" "F.Mask" "F.Paste")
			(net 456 "/USB/BDBUS0")
			(pinfunction "BDBUS0")
			(pintype "bidirectional")
		)
		(pad "20" smd rect
			(at -3.6 4.35 90)
			(size 0.7 0.2)
			(layers "F.Cu" "F.Mask" "F.Paste")
			(net 457 "/USB/BDBUS1")
			(pinfunction "BDBUS1")
			(pintype "bidirectional")
		)
		(pad "21" smd rect
			(at -3.2 4.35 90)
			(size 0.7 0.2)
			(layers "F.Cu" "F.Mask" "F.Paste")
			(net 458 "/USB/BDBUS2")
			(pinfunction "BDBUS2")
			(pintype "bidirectional")
		)
		(pad "22" smd rect
			(at -2.8 4.35 90)
			(size 0.7 0.2)
			(layers "F.Cu" "F.Mask" "F.Paste")
			(net 425 "unconnected-(U905-BDBUS3-Pad22)")
			(pinfunction "BDBUS3")
			(pintype "bidirectional+no_connect")
		)
		(pad "23" smd rect
			(at -2.4 4.35 90)
			(size 0.7 0.2)
			(layers "F.Cu" "F.Mask" "F.Paste")
			(net 424 "unconnected-(U905-BDBUS4-Pad23)")
			(pinfunction "BDBUS4")
			(pintype "bidirectional+no_connect")
		)
		(pad "24" smd rect
			(at -2 4.35 90)
			(size 0.7 0.2)
			(layers "F.Cu" "F.Mask" "F.Paste")
			(net 463 "/USB/I2C_EN")
			(pinfunction "BDBUS5")
			(pintype "bidirectional")
		)
		(pad "25" smd rect
			(at -1.6 4.35 90)
			(size 0.7 0.2)
			(layers "F.Cu" "F.Mask" "F.Paste")
			(net 423 "unconnected-(U905-BDBUS6-Pad25)")
			(pinfunction "BDBUS6")
			(pintype "bidirectional+no_connect")
		)
		(pad "26" smd rect
			(at -1.2 4.35 90)
			(size 0.7 0.2)
			(layers "F.Cu" "F.Mask" "F.Paste")
			(net 422 "unconnected-(U905-BDBUS7-Pad26)")
			(pinfunction "BDBUS7")
			(pintype "bidirectional+no_connect")
		)
		(pad "27" smd rect
			(at -0.8 4.35 90)
			(size 0.7 0.2)
			(layers "F.Cu" "F.Mask" "F.Paste")
			(net 30 "/USB/USB_1V2")
			(pinfunction "VCORE")
			(pintype "passive")
		)
		(pad "28" smd rect
			(at -0.4 4.35 90)
			(size 0.7 0.2)
			(layers "F.Cu" "F.Mask" "F.Paste")
			(net 27 "/USB/USB_3V3")
			(pinfunction "VCCIO")
			(pintype "passive")
		)
		(pad "29" smd rect
			(at 0 4.35 90)
			(size 0.7 0.2)
			(layers "F.Cu" "F.Mask" "F.Paste")
			(net 114 "Net-(U905-OSCI)")
			(pinfunction "OSCI")
			(pintype "input")
		)
		(pad "30" smd rect
			(at 0.4 4.35 90)
			(size 0.7 0.2)
			(layers "F.Cu" "F.Mask" "F.Paste")
			(net 115 "Net-(U905-OSCO)")
			(pinfunction "OSCO")
			(pintype "output")
		)
		(pad "31" smd rect
			(at 0.8 4.35 90)
			(size 0.7 0.2)
			(layers "F.Cu" "F.Mask" "F.Paste")
			(net 3 "GND")
			(pinfunction "GND")
			(pintype "passive")
		)
		(pad "32" smd rect
			(at 1.2 4.35 90)
			(size 0.7 0.2)
			(layers "F.Cu" "F.Mask" "F.Paste")
			(net 31 "/USB/VREGIN")
			(pinfunction "VREGIN")
			(pintype "input")
		)
		(pad "33" smd rect
			(at 1.6 4.35 90)
			(size 0.7 0.2)
			(layers "F.Cu" "F.Mask" "F.Paste")
			(net 30 "/USB/USB_1V2")
			(pinfunction "VREGOUT")
			(pintype "output")
		)
		(pad "34" smd rect
			(at 2 4.35 90)
			(size 0.7 0.2)
			(layers "F.Cu" "F.Mask" "F.Paste")
			(net 421 "unconnected-(U905-FSOURCE-Pad34)")
			(pinfunction "FSOURCE")
			(pintype "input+no_connect")
		)
		(pad "35" smd rect
			(at 2.4 4.35 90)
			(size 0.7 0.2)
			(layers "F.Cu" "F.Mask" "F.Paste")
			(net 420 "unconnected-(U905-VPP-Pad35)")
			(pinfunction "VPP")
			(pintype "input+no_connect")
		)
		(pad "36" smd rect
			(at 2.8 4.35 90)
			(size 0.7 0.2)
			(layers "F.Cu" "F.Mask" "F.Paste")
			(net 189 "/Compute module/UART.2.RX")
			(pinfunction "CDBUS0")
			(pintype "bidirectional")
		)
		(pad "37" smd rect
			(at 3.2 4.35 90)
			(size 0.7 0.2)
			(layers "F.Cu" "F.Mask" "F.Paste")
			(net 188 "/Compute module/UART.2.TX")
			(pinfunction "CDBUS1")
			(pintype "bidirectional")
		)
		(pad "38" smd rect
			(at 3.6 4.35 90)
			(size 0.7 0.2)
			(layers "F.Cu" "F.Mask" "F.Paste")
			(net 419 "unconnected-(U905-CDBUS2-Pad38)")
			(pinfunction "CDBUS2")
			(pintype "bidirectional+no_connect")
		)
		(pad "39" smd rect
			(at 4.35 3.6)
			(size 0.7 0.2)
			(layers "F.Cu" "F.Mask" "F.Paste")
			(net 418 "unconnected-(U905-CDBUS3-Pad39)")
			(pinfunction "CDBUS3")
			(pintype "bidirectional+no_connect")
		)
		(pad "40" smd rect
			(at 4.35 3.2)
			(size 0.7 0.2)
			(layers "F.Cu" "F.Mask" "F.Paste")
			(net 417 "unconnected-(U905-CDBUS4-Pad40)")
			(pinfunction "CDBUS4")
			(pintype "bidirectional+no_connect")
		)
		(pad "41" smd rect
			(at 4.35 2.8)
			(size 0.7 0.2)
			(layers "F.Cu" "F.Mask" "F.Paste")
			(net 27 "/USB/USB_3V3")
			(pinfunction "VCCIO")
			(pintype "passive")
		)
		(pad "42" smd rect
			(at 4.35 2.4)
			(size 0.7 0.2)
			(layers "F.Cu" "F.Mask" "F.Paste")
			(net 416 "unconnected-(U905-CDBUS5-Pad42)")
			(pinfunction "CDBUS5")
			(pintype "bidirectional+no_connect")
		)
		(pad "43" smd rect
			(at 4.35 2)
			(size 0.7 0.2)
			(layers "F.Cu" "F.Mask" "F.Paste")
			(net 415 "unconnected-(U905-CDBUS6-Pad43)")
			(pinfunction "CDBUS6")
			(pintype "bidirectional+no_connect")
		)
		(pad "44" smd rect
			(at 4.35 1.6)
			(size 0.7 0.2)
			(layers "F.Cu" "F.Mask" "F.Paste")
			(net 414 "unconnected-(U905-CDBUS7-Pad44)")
			(pinfunction "CDBUS7")
			(pintype "bidirectional+no_connect")
		)
		(pad "45" smd rect
			(at 4.35 1.2)
			(size 0.7 0.2)
			(layers "F.Cu" "F.Mask" "F.Paste")
			(net 486 "Net-(D911-C)")
			(pinfunction "~{SUSPEND}")
			(pintype "output")
		)
		(pad "46" smd rect
			(at 4.35 0.8)
			(size 0.7 0.2)
			(layers "F.Cu" "F.Mask" "F.Paste")
			(net 384 "Net-(U905-GPIO6)")
			(pinfunction "GPIO6")
			(pintype "bidirectional")
		)
		(pad "47" smd rect
			(at 4.35 0.4)
			(size 0.7 0.2)
			(layers "F.Cu" "F.Mask" "F.Paste")
			(net 30 "/USB/USB_1V2")
			(pinfunction "VCORE")
			(pintype "passive")
		)
		(pad "48" smd rect
			(at 4.35 0)
			(size 0.7 0.2)
			(layers "F.Cu" "F.Mask" "F.Paste")
			(net 191 "/Compute module/UART.3.RX")
			(pinfunction "DDBUS0")
			(pintype "bidirectional")
		)
		(pad "49" smd rect
			(at 4.35 -0.4)
			(size 0.7 0.2)
			(layers "F.Cu" "F.Mask" "F.Paste")
			(net 190 "/Compute module/UART.3.TX")
			(pinfunction "DDBUS1")
			(pintype "bidirectional")
		)
		(pad "50" smd rect
			(at 4.35 -0.8)
			(size 0.7 0.2)
			(layers "F.Cu" "F.Mask" "F.Paste")
			(net 413 "unconnected-(U905-DDBUS2-Pad50)")
			(pinfunction "DDBUS2")
			(pintype "bidirectional+no_connect")
		)
		(pad "51" smd rect
			(at 4.35 -1.2)
			(size 0.7 0.2)
			(layers "F.Cu" "F.Mask" "F.Paste")
			(net 412 "unconnected-(U905-DDBUS3-Pad51)")
			(pinfunction "DDBUS3")
			(pintype "bidirectional+no_connect")
		)
		(pad "52" smd rect
			(at 4.35 -1.6)
			(size 0.7 0.2)
			(layers "F.Cu" "F.Mask" "F.Paste")
			(net 411 "unconnected-(U905-DDBUS4-Pad52)")
			(pinfunction "DDBUS4")
			(pintype "bidirectional+no_connect")
		)
		(pad "53" smd rect
			(at 4.35 -2)
			(size 0.7 0.2)
			(layers "F.Cu" "F.Mask" "F.Paste")
			(net 410 "unconnected-(U905-DDBUS5-Pad53)")
			(pinfunction "DDBUS5")
			(pintype "bidirectional+no_connect")
		)
		(pad "54" smd rect
			(at 4.35 -2.4)
			(size 0.7 0.2)
			(layers "F.Cu" "F.Mask" "F.Paste")
			(net 27 "/USB/USB_3V3")
			(pinfunction "VCCIO")
			(pintype "passive")
		)
		(pad "55" smd rect
			(at 4.35 -2.8)
			(size 0.7 0.2)
			(layers "F.Cu" "F.Mask" "F.Paste")
			(net 3 "GND")
			(pinfunction "GND")
			(pintype "passive")
		)
		(pad "56" smd rect
			(at 4.35 -3.2)
			(size 0.7 0.2)
			(layers "F.Cu" "F.Mask" "F.Paste")
			(net 409 "unconnected-(U905-DDBUS6-Pad56)")
			(pinfunction "DDBUS6")
			(pintype "bidirectional+no_connect")
		)
		(pad "57" smd rect
			(at 4.35 -3.6)
			(size 0.7 0.2)
			(layers "F.Cu" "F.Mask" "F.Paste")
			(net 408 "unconnected-(U905-DDBUS7-Pad57)")
			(pinfunction "DDBUS7")
			(pintype "bidirectional+no_connect")
		)
		(pad "58" smd rect
			(at 3.6 -4.35 90)
			(size 0.7 0.2)
			(layers "F.Cu" "F.Mask" "F.Paste")
			(net 385 "Net-(U905-GPIO7)")
			(pinfunction "GPIO7")
			(pintype "bidirectional")
		)
		(pad "59" smd rect
			(at 3.2 -4.35 90)
			(size 0.7 0.2)
			(layers "F.Cu" "F.Mask" "F.Paste")
			(net 450 "Net-(U905-GPIO2)")
			(pinfunction "GPIO2")
			(pintype "bidirectional")
		)
		(pad "60" smd rect
			(at 2.8 -4.35 90)
			(size 0.7 0.2)
			(layers "F.Cu" "F.Mask" "F.Paste")
			(net 449 "Net-(U905-GPIO1)")
			(pinfunction "GPIO1")
			(pintype "bidirectional")
		)
		(pad "61" smd rect
			(at 2.4 -4.35 90)
			(size 0.7 0.2)
			(layers "F.Cu" "F.Mask" "F.Paste")
			(net 448 "Net-(U905-GPIO0)")
			(pinfunction "GPIO0")
			(pintype "bidirectional")
		)
		(pad "62" smd rect
			(at 2 -4.35 90)
			(size 0.7 0.2)
			(layers "F.Cu" "F.Mask" "F.Paste")
			(net 32 "/USB/VCC_USB")
			(pinfunction "VCC_USB")
			(pintype "power_in")
		)
		(pad "63" smd rect
			(at 1.6 -4.35 90)
			(size 0.7 0.2)
			(layers "F.Cu" "F.Mask" "F.Paste")
			(net 277 "/USB/USBD.D_N")
			(pinfunction "DM")
			(pintype "bidirectional")
		)
		(pad "64" smd rect
			(at 1.2 -4.35 90)
			(size 0.7 0.2)
			(layers "F.Cu" "F.Mask" "F.Paste")
			(net 278 "/USB/USBD.D_P")
			(pinfunction "DP")
			(pintype "bidirectional")
		)
		(pad "65" smd rect
			(at 0.8 -4.35 90)
			(size 0.7 0.2)
			(layers "F.Cu" "F.Mask" "F.Paste")
			(net 378 "Net-(U905-REF)")
			(pinfunction "REF")
			(pintype "input")
		)
		(pad "66" smd rect
			(at 0.4 -4.35 90)
			(size 0.7 0.2)
			(layers "F.Cu" "F.Mask" "F.Paste")
			(net 211 "/USB/VCC_PD")
			(pinfunction "VCC_PD")
			(pintype "power_in")
		)
		(pad "67" smd rect
			(at 0 -4.35 90)
			(size 0.7 0.2)
			(layers "F.Cu" "F.Mask" "F.Paste")
			(net 208 "/USB/USBD_CC2")
			(pinfunction "PD1_CC2")
			(pintype "bidirectional")
		)
		(pad "68" smd rect
			(at -0.4 -4.35 90)
			(size 0.7 0.2)
			(layers "F.Cu" "F.Mask" "F.Paste")
			(net 29 "/USB/USBD_SVBUS")
			(pinfunction "PD1_SVBUS")
			(pintype "input")
		)
		(pad "69" smd rect
			(at -0.8 -4.35 90)
			(size 0.7 0.2)
			(layers "F.Cu" "F.Mask" "F.Paste")
			(net 211 "/USB/VCC_PD")
			(pinfunction "PD1_VCONN")
			(pintype "power_in")
		)
		(pad "70" smd rect
			(at -1.2 -4.35 90)
			(size 0.7 0.2)
			(layers "F.Cu" "F.Mask" "F.Paste")
			(net 207 "/USB/USBD_CC1")
			(pinfunction "PD1_CC1")
			(pintype "bidirectional")
		)
		(pad "71" smd rect
			(at -1.6 -4.35 90)
			(size 0.7 0.2)
			(layers "F.Cu" "F.Mask" "F.Paste")
			(net 439 "Net-(U905-PD2_CC1)")
			(pinfunction "PD2_CC1")
			(pintype "bidirectional")
		)
		(pad "72" smd rect
			(at -2 -4.35 90)
			(size 0.7 0.2)
			(layers "F.Cu" "F.Mask" "F.Paste")
			(net 438 "Net-(U905-PD2_SVBUS)")
			(pinfunction "PD2_SVBUS")
			(pintype "input")
		)
		(pad "73" smd rect
			(at -2.4 -4.35 90)
			(size 0.7 0.2)
			(layers "F.Cu" "F.Mask" "F.Paste")
			(net 440 "Net-(U905-PD2_CC2)")
			(pinfunction "PD2_CC2")
			(pintype "bidirectional")
		)
		(pad "74" smd rect
			(at -2.8 -4.35 90)
			(size 0.7 0.2)
			(layers "F.Cu" "F.Mask" "F.Paste")
			(net 30 "/USB/USB_1V2")
			(pinfunction "VCORE")
			(pintype "passive")
		)
		(pad "75" smd rect
			(at -3.2 -4.35 90)
			(size 0.7 0.2)
			(layers "F.Cu" "F.Mask" "F.Paste")
			(net 488 "Net-(D912-C)")
			(pinfunction "~{PWREN}")
			(pintype "output")
		)
		(pad "76" smd rect
			(at -3.6 -4.35 90)
			(size 0.7 0.2)
			(layers "F.Cu" "F.Mask" "F.Paste")
			(net 283 "/USB/EECS")
			(pinfunction "EECS")
			(pintype "bidirectional")
		)
		(pad "77" smd rect
			(at 0 0)
			(size 6.3 6.3)
			(layers "F.Cu" "F.Mask")
			(net 3 "GND")
			(pinfunction "GND")
			(pintype "passive")
		)
	)
)
